# S9S_MB_2U (Grand Teton) — schematic netlist excerpt (pin names and nets, part order shuffled) for the footprints in the layout excerpt that follows; sources: Cadence DE-HDL packaged netlist, KiCad conversion of 03242023_DA0F0TMBIJ0_F0T_Motherboard_J_brd_V01_OCP.brd

R3362  Q_RES  1K 1% CHIP  pkg 0402LF  page 167 : A = PD_P2E_BUF2_ENSMB ; B = GND

U206  LT6700CS61TRPBF  LT6700CS6-1#TRPBF IC  pkg TSOT23-6_0-95_2-9X1-625  page 306
  OUTA  = FM_UV_ADR_TRIGGER_N
  GND  = GND
  \ina+\  = A_P12V_STBY_ADR_TRIGGER
  \inb-\  = A_P12V_STBY_FP_TRIGGER
  VS  = U206_VDD
  OUTB  = A_P12V_STBY_FPH_GATE

(kicad_pcb
	(version 20260206)
	(generator "pcbnew")
	(generator_version "10.0")
	(general
		(thickness 1.6)
		(legacy_teardrops no)
	)
	(paper "A4")
	(title_block
		(title "03242023_DA0F0TMBIJ0_F0T_Motherboard_J_brd_V01_OCP.brd")
		(comment 1 "Grand Teton / footprints 905-906 of 6105")
	)
	(layers
		(0 "F.Cu" signal "TOP")
		(4 "In1.Cu" signal "GND")
		(6 "In2.Cu" signal "IN1")
		(8 "In3.Cu" signal "GND1")
		(10 "In4.Cu" signal "IN2")
		(12 "In5.Cu" signal "GND2")
		(14 "In6.Cu" signal "IN3")
		(16 "In7.Cu" signal "GND3")
		(18 "In8.Cu" signal "VCC")
		(20 "In9.Cu" signal "VCC1")
		(22 "In10.Cu" signal "GND4")
		(24 "In11.Cu" signal "IN4")
		(26 "In12.Cu" signal "GND5")
		(28 "In13.Cu" signal "IN5")
		(30 "In14.Cu" signal "GND6")
		(32 "In15.Cu" signal "IN6")
		(34 "In16.Cu" signal "GND7")
		(2 "B.Cu" signal "BOTTOM")
		(9 "F.Adhes" user "F.Adhesive")
		(11 "B.Adhes" user "B.Adhesive")
		(13 "F.Paste" user "Package Geometry/Pastemask Top")
		(15 "B.Paste" user "Package Geometry/Pastemask Bottom")
		(5 "F.SilkS" user "Ref Des/Silkscreen Top")
		(7 "B.SilkS" user "Ref Des/Silkscreen Bottom")
		(1 "F.Mask" user "Board Geometry/Soldermask Top")
		(3 "B.Mask" user "Board Geometry/Soldermask Bottom")
		(17 "Dwgs.User" user "User.Drawings")
		(19 "Cmts.User" user "User.Comments")
		(21 "Eco1.User" user "User.Eco1")
		(23 "Eco2.User" user "User.Eco2")
		(25 "Edge.Cuts" user "Board Geometry/Outline")
		(27 "Margin" user)
		(31 "F.CrtYd" user "Package Geometry/Place Bound Top")
		(29 "B.CrtYd" user "Package Geometry/Place Bound Bottom")
		(35 "F.Fab" user "Ref Des/Assembly Top")
		(33 "B.Fab" user "Ref Des/Assembly Bottom")
	)
	(footprint ""
		(layer "F.Cu")
		(at 215.351614 -99.79152)
		(property "Reference" "U206"
			(at -2.2606 -2.174748 0)
			(unlocked yes)
			(layer "F.SilkS")
			(effects
				(font
					(size 0.7874 0.5842)
					(thickness 0.1524)
				)
				(justify left)
			)
		)
		(property "Value" ""
			(at 0 0 0)
			(layer "F.Fab")
			(effects
				(font
					(size 1.27 1.27)
				)
			)
		)
		(duplicate_pad_numbers_are_jumpers no)
		(fp_line
			(start -2.046478 -1.450086)
			(end -2.046478 1.450086)
			(stroke
				(width 0.1524)
				(type default)
			)
			(layer "F.SilkS")
		)
		(fp_line
			(start -2.046478 1.450086)
			(end 2.046478 1.450086)
			(stroke
				(width 0.1524)
				(type default)
			)
			(layer "F.SilkS")
		)
		(fp_line
			(start -0.484886 -1.450086)
			(end -2.046478 -1.450086)
			(stroke
				(width 0.1524)
				(type default)
			)
			(layer "F.SilkS")
		)
		(fp_line
			(start 0 -0.762)
			(end -0.484886 -1.450086)
			(stroke
				(width 0.1524)
				(type default)
			)
			(layer "F.SilkS")
		)
		(fp_line
			(start 0.484886 -1.450086)
			(end 0 -0.762)
			(stroke
				(width 0.1524)
				(type default)
			)
			(layer "F.SilkS")
		)
		(fp_line
			(start 2.046478 -1.450086)
			(end 0.484886 -1.450086)
			(stroke
				(width 0.1524)
				(type default)
			)
			(layer "F.SilkS")
		)
		(fp_line
			(start 2.046478 1.450086)
			(end 2.046478 -1.450086)
			(stroke
				(width 0.1524)
				(type default)
			)
			(layer "F.SilkS")
		)
		(fp_poly
			(pts
				(xy -3.2512 -0.44196) (xy -3.2512 -1.45796) (xy -2.2352 -0.94996)
			)
			(stroke
				(width 0)
				(type default)
			)
			(fill yes)
			(layer "F.SilkS")
		)
		(fp_line
			(start -0.87503 -1.450086)
			(end -0.87503 1.450086)
			(stroke
				(width 0.1)
				(type default)
			)
			(layer "F.Fab")
		)
		(fp_line
			(start -0.87503 1.450086)
			(end 0.87503 1.450086)
			(stroke
				(width 0.1)
				(type default)
			)
			(layer "F.Fab")
		)
		(fp_line
			(start 0.87503 -1.450086)
			(end -0.87503 -1.450086)
			(stroke
				(width 0.1)
				(type default)
			)
			(layer "F.Fab")
		)
		(fp_line
			(start 0.87503 1.450086)
			(end 0.87503 -1.450086)
			(stroke
				(width 0.1)
				(type default)
			)
			(layer "F.Fab")
		)
		(fp_poly
			(pts
				(xy -3.2512 -0.44196) (xy -3.2512 -1.45796) (xy -2.2352 -0.94996)
			)
			(stroke
				(width 0)
				(type default)
			)
			(fill yes)
			(layer "F.Fab")
		)
		(pad "1" smd rect
			(at -1.309878 -0.94996 90)
			(size 0.635 1.2192)
			(layers "F.Cu" "F.Mask" "F.Paste")
			(net "FM_UV_ADR_TRIGGER_N")
		)
		(pad "2" smd rect
			(at -1.309878 0 90)
			(size 0.635 1.2192)
			(layers "F.Cu" "F.Mask" "F.Paste")
			(net "GND")
		)
		(pad "3" smd rect
			(at -1.309878 0.94996 90)
			(size 0.635 1.2192)
			(layers "F.Cu" "F.Mask" "F.Paste")
			(net "A_P12V_STBY_ADR_TRIGGER")
		)
		(pad "4" smd rect
			(at 1.309878 0.94996 90)
			(size 0.635 1.2192)
			(layers "F.Cu" "F.Mask" "F.Paste")
			(net "A_P12V_STBY_FP_TRIGGER")
		)
		(pad "5" smd rect
			(at 1.309878 0 90)
			(size 0.635 1.2192)
			(layers "F.Cu" "F.Mask" "F.Paste")
			(net "U206_VDD")
		)
		(pad "6" smd rect
			(at 1.309878 -0.94996 90)
			(size 0.635 1.2192)
			(layers "F.Cu" "F.Mask" "F.Paste")
			(net "A_P12V_STBY_FPH_GATE")
		)
	)
	(footprint ""
		(layer "F.Cu")
		(at 46.067472 -392.183112)
		(property "Reference" "R3362"
			(at 0 0 0)
			(layer "F.SilkS")
			(hide yes)
			(effects
				(font
					(size 1.27 1.27)
				)
			)
		)
		(property "Value" ""
			(at 0 0 0)
			(layer "F.Fab")
			(effects
				(font
					(size 1.27 1.27)
				)
			)
		)
		(duplicate_pad_numbers_are_jumpers no)
		(fp_line
			(start -0.7874 -0.4064)
			(end 0.7874 -0.4064)
			(stroke
				(width 0.1524)
				(type default)
			)
			(layer "F.SilkS")
		)
		(fp_line
			(start -0.7874 0.4064)
			(end -0.7874 -0.4064)
			(stroke
				(width 0.1524)
				(type default)
			)
			(layer "F.SilkS")
		)
		(fp_line
			(start 0.7874 -0.4064)
			(end 0.7874 0.4064)
			(stroke
				(width 0.1524)
				(type default)
			)
			(layer "F.SilkS")
		)
		(fp_line
			(start 0.7874 0.4064)
			(end -0.7874 0.4064)
			(stroke
				(width 0.1524)
				(type default)
			)
			(layer "F.SilkS")
		)
		(fp_line
			(start -0.67945 -0.305054)
			(end -0.12065 -0.305054)
			(stroke
				(width 0.1)
				(type default)
			)
			(layer "F.Fab")
		)
		(fp_line
			(start -0.67945 0.3048)
			(end -0.67945 -0.305054)
			(stroke
				(width 0.1)
				(type default)
			)
			(layer "F.Fab")
		)
		(fp_line
			(start -0.12065 -0.305054)
			(end -0.12065 -0.2794)
			(stroke
				(width 0.1)
				(type default)
			)
			(layer "F.Fab")
		)
		(fp_line
			(start -0.12065 -0.2794)
			(end 0.12065 -0.2794)
			(stroke
				(width 0.1)
				(type default)
			)
			(layer "F.Fab")
		)
		(fp_line
			(start -0.12065 0.2794)
			(end -0.12065 0.3048)
			(stroke
				(width 0.1)
				(type default)
			)
			(layer "F.Fab")
		)
		(fp_line
			(start -0.12065 0.3048)
			(end -0.67945 0.3048)
			(stroke
				(width 0.1)
				(type default)
			)
			(layer "F.Fab")
		)
		(fp_line
			(start 0.120396 0.2794)
			(end -0.12065 0.2794)
			(stroke
				(width 0.1)
				(type default)
			)
			(layer "F.Fab")
		)
		(fp_line
			(start 0.120396 0.3048)
			(end 0.120396 0.2794)
			(stroke
				(width 0.1)
				(type default)
			)
			(layer "F.Fab")
		)
		(fp_line
			(start 0.12065 -0.3048)
			(end 0.67945 -0.3048)
			(stroke
				(width 0.1)
				(type default)
			)
			(layer "F.Fab")
		)
		(fp_line
			(start 0.12065 -0.2794)
			(end 0.12065 -0.3048)
			(stroke
				(width 0.1)
				(type default)
			)
			(layer "F.Fab")
		)
		(fp_line
			(start 0.67945 -0.3048)
			(end 0.67945 0.3048)
			(stroke
				(width 0.1)
				(type default)
			)
			(layer "F.Fab")
		)
		(fp_line
			(start 0.67945 0.3048)
			(end 0.120396 0.3048)
			(stroke
				(width 0.1)
				(type default)
			)
			(layer "F.Fab")
		)
		(pad "1" smd circle
			(at -0.40005 0)
			(size 0 0)
			(layers "F.Cu" "F.Mask" "F.Paste")
			(net "PD_P2E_BUF2_ENSMB")
		)
		(pad "2" smd circle
			(at 0.40005 0)
			(size 0 0)
			(layers "F.Cu" "F.Mask" "F.Paste")
			(net "GND")
		)
	)
)
